(kicad_pcb
	(version 20260206)
	(generator "pcbnew")
	(generator_version "10.0")
	(general
		(thickness 1.6)
		(legacy_teardrops no)
	)
	(paper "A4")
	(title_block
		(title "Bryce Canyon_IOM_IOC_16318-2_OCP.brd")
		(comment 1 "Bryce Canyon / footprint 592 of 1605 (U1), pads 120-234 of 896")
	)
	(layers
		(0 "F.Cu" signal "TOP")
		(4 "In1.Cu" signal "L2GND")
		(6 "In2.Cu" signal "L3")
		(8 "In3.Cu" signal "L4VCC")
		(10 "In4.Cu" signal "L5VCC")
		(12 "In5.Cu" signal "L6")
		(14 "In6.Cu" signal "L7GND")
		(2 "B.Cu" signal "BOTTOM")
		(9 "F.Adhes" user "F.Adhesive")
		(11 "B.Adhes" user "B.Adhesive")
		(13 "F.Paste" user "Package Geometry/Pastemask Top")
		(15 "B.Paste" user "Package Geometry/Pastemask Bottom")
		(5 "F.SilkS" user "Ref Des/Silkscreen Top")
		(7 "B.SilkS" user "Ref Des/Silkscreen Bottom")
		(1 "F.Mask" user "Board Geometry/Soldermask Top")
		(3 "B.Mask" user "Board Geometry/Soldermask Bottom")
		(17 "Dwgs.User" user "User.Drawings")
		(19 "Cmts.User" user "User.Comments")
		(21 "Eco1.User" user "User.Eco1")
		(23 "Eco2.User" user "User.Eco2")
		(25 "Edge.Cuts" user "Board Geometry/Outline")
		(27 "Margin" user)
		(31 "F.CrtYd" user "Package Geometry/Place Bound Top")
		(29 "B.CrtYd" user "Package Geometry/Place Bound Bottom")
		(35 "F.Fab" user "Ref Des/Assembly Top")
		(33 "B.Fab" user "Ref Des/Assembly Bottom")
	)
	(footprint ""
		(layer "F.Cu")
		(at 192.79997 -65.099946 180)
		(property "Reference" "U1"
			(at 0 0 180)
			(layer "F.SilkS")
			(hide yes)
			(effects
				(font
					(size 1.27 1.27)
				)
			)
		)
		(property "Value" "SAS3008C0-1-DB-500020657-1-GP"
			(at -20.374102 -5.0292 180)
			(unlocked yes)
			(layer "F.Fab")
			(hide yes)
			(effects
				(font
					(size 1.016 1.016)
					(thickness 0.1524)
				)
			)
		)
		(property "Device Type" "BGA896D25H78"
			(at -20.374102 -6.5532 180)
			(unlocked yes)
			(layer "F.Fab")
			(hide yes)
			(effects
				(font
					(size 1.016 1.016)
					(thickness 0.1524)
				)
			)
		)
		(duplicate_pad_numbers_are_jumpers no)
		(pad "AD2" smd circle
			(at -10.80008 6.800088 180)
			(size 0.3556 0.3556)
			(layers "F.Cu" "F.Mask" "F.Paste")
			(net "PHY_IOC_TO_CON_A_3_DN_C")
		)
		(pad "AD3" smd circle
			(at -9.99998 6.800088 180)
			(size 0.3556 0.3556)
			(layers "F.Cu" "F.Mask" "F.Paste")
			(net "GND")
		)
		(pad "AD4" smd circle
			(at -9.19988 6.800088 180)
			(size 0.3556 0.3556)
			(layers "F.Cu" "F.Mask" "F.Paste")
			(net "PHY_CON_A_TO_IOC_3_DP")
		)
		(pad "AD5" smd circle
			(at -8.400034 6.800088 180)
			(size 0.3556 0.3556)
			(layers "F.Cu" "F.Mask" "F.Paste")
			(net "PHY_CON_A_TO_IOC_3_DN")
		)
		(pad "AD6" smd circle
			(at -7.599934 6.800088 180)
			(size 0.3556 0.3556)
			(layers "F.Cu" "F.Mask" "F.Paste")
			(net "GND")
		)
		(pad "AD7" smd circle
			(at -6.800088 6.800088 180)
			(size 0.3556 0.3556)
			(layers "F.Cu" "F.Mask" "F.Paste")
			(net "SAS0_AVDD")
		)
		(pad "AD8" smd circle
			(at -5.999988 6.800088 180)
			(size 0.3556 0.3556)
			(layers "F.Cu" "F.Mask" "F.Paste")
			(net "GND")
		)
		(pad "AD9" smd circle
			(at -5.199888 6.800088 180)
			(size 0.3556 0.3556)
			(layers "F.Cu" "F.Mask" "F.Paste")
			(net "PCE_AVDD")
		)
		(pad "AD10" smd circle
			(at -4.400042 6.800088 180)
			(size 0.3556 0.3556)
			(layers "F.Cu" "F.Mask" "F.Paste")
			(net "GND")
		)
		(pad "AD11" smd circle
			(at -3.599942 6.800088 180)
			(size 0.3556 0.3556)
			(layers "F.Cu" "F.Mask" "F.Paste")
			(net "PCE_AVDD")
		)
		(pad "AD12" smd circle
			(at -2.800096 6.800088 180)
			(size 0.3556 0.3556)
			(layers "F.Cu" "F.Mask" "F.Paste")
			(net "GND")
		)
		(pad "AD13" smd circle
			(at -1.999996 6.800088 180)
			(size 0.3556 0.3556)
			(layers "F.Cu" "F.Mask" "F.Paste")
			(net "PCE_AVDD")
		)
		(pad "AD14" smd circle
			(at -1.199896 6.800088 180)
			(size 0.3556 0.3556)
			(layers "F.Cu" "F.Mask" "F.Paste")
			(net "GND")
		)
		(pad "AD15" smd circle
			(at -0.40005 6.800088 180)
			(size 0.3556 0.3556)
			(layers "F.Cu" "F.Mask" "F.Paste")
			(net "PCE_AVDD")
		)
		(pad "AD16" smd circle
			(at 0.40005 6.800088 180)
			(size 0.3556 0.3556)
			(layers "F.Cu" "F.Mask" "F.Paste")
			(net "GND")
		)
		(pad "AD17" smd circle
			(at 1.199896 6.800088 180)
			(size 0.3556 0.3556)
			(layers "F.Cu" "F.Mask" "F.Paste")
			(net "GND")
		)
		(pad "AD18" smd circle
			(at 1.999996 6.800088 180)
			(size 0.3556 0.3556)
			(layers "F.Cu" "F.Mask" "F.Paste")
			(net "GND")
		)
		(pad "AD19" smd circle
			(at 2.800096 6.800088 180)
			(size 0.3556 0.3556)
			(layers "F.Cu" "F.Mask" "F.Paste")
			(net "GND")
		)
		(pad "AD20" smd circle
			(at 3.599942 6.800088 180)
			(size 0.3556 0.3556)
			(layers "F.Cu" "F.Mask" "F.Paste")
			(net "GND")
		)
		(pad "AD21" smd circle
			(at 4.400042 6.800088 180)
			(size 0.3556 0.3556)
			(layers "F.Cu" "F.Mask" "F.Paste")
			(net "GND")
		)
		(pad "AD22" smd circle
			(at 5.199888 6.800088 180)
			(size 0.3556 0.3556)
			(layers "F.Cu" "F.Mask" "F.Paste")
			(net "GND")
		)
		(pad "AD23" smd circle
			(at 5.999988 6.800088 180)
			(size 0.3556 0.3556)
			(layers "F.Cu" "F.Mask" "F.Paste")
			(net "GND")
		)
		(pad "AD24" smd circle
			(at 6.800088 6.800088 180)
			(size 0.3556 0.3556)
			(layers "F.Cu" "F.Mask" "F.Paste")
			(net "GND")
		)
		(pad "AD25" smd circle
			(at 7.599934 6.800088 180)
			(size 0.3556 0.3556)
			(layers "F.Cu" "F.Mask" "F.Paste")
			(net "GND")
		)
		(pad "AD26" smd circle
			(at 8.400034 6.800088 180)
			(size 0.3556 0.3556)
			(layers "F.Cu" "F.Mask" "F.Paste")
			(net "P1V8")
		)
		(pad "AD27" smd circle
			(at 9.19988 6.800088 180)
			(size 0.3556 0.3556)
			(layers "F.Cu" "F.Mask" "F.Paste")
			(net "GND")
		)
		(pad "AD28" smd circle
			(at 9.99998 6.800088 180)
			(size 0.3556 0.3556)
			(layers "F.Cu" "F.Mask" "F.Paste")
			(net "IOC_GPIO_29")
		)
		(pad "AD29" smd circle
			(at 10.80008 6.800088 180)
			(size 0.3556 0.3556)
			(layers "F.Cu" "F.Mask" "F.Paste")
			(net "IOC_GPIO_27")
		)
		(pad "AD30" smd circle
			(at 11.599926 6.800088 180)
			(size 0.3556 0.3556)
			(layers "F.Cu" "F.Mask" "F.Paste")
			(net "IOC_GPIO_17")
		)
		(pad "AE1" smd circle
			(at -11.599926 7.599934 180)
			(size 0.3556 0.3556)
			(layers "F.Cu" "F.Mask" "F.Paste")
			(net "PHY_IOC_TO_CON_A_2_DP_C")
		)
		(pad "AE2" smd circle
			(at -10.80008 7.599934 180)
			(size 0.3556 0.3556)
			(layers "F.Cu" "F.Mask" "F.Paste")
			(net "PHY_IOC_TO_CON_A_2_DN_C")
		)
		(pad "AE3" smd circle
			(at -9.99998 7.599934 180)
			(size 0.3556 0.3556)
			(layers "F.Cu" "F.Mask" "F.Paste")
			(net "GND")
		)
		(pad "AE4" smd circle
			(at -9.19988 7.599934 180)
			(size 0.3556 0.3556)
			(layers "F.Cu" "F.Mask" "F.Paste")
			(net "PHY_CON_A_TO_IOC_2_DP")
		)
		(pad "AE5" smd circle
			(at -8.400034 7.599934 180)
			(size 0.3556 0.3556)
			(layers "F.Cu" "F.Mask" "F.Paste")
			(net "PHY_CON_A_TO_IOC_2_DN")
		)
		(pad "AE6" smd circle
			(at -7.599934 7.599934 180)
			(size 0.3556 0.3556)
			(layers "F.Cu" "F.Mask" "F.Paste")
			(net "GND")
		)
		(pad "AE7" smd circle
			(at -6.800088 7.599934 180)
			(size 0.3556 0.3556)
			(layers "F.Cu" "F.Mask" "F.Paste")
			(net "GND")
		)
		(pad "AE8" smd circle
			(at -5.999988 7.599934 180)
			(size 0.3556 0.3556)
			(layers "F.Cu" "F.Mask" "F.Paste")
			(net "PCE_VDDH")
		)
		(pad "AE9" smd circle
			(at -5.199888 7.599934 180)
			(size 0.3556 0.3556)
			(layers "F.Cu" "F.Mask" "F.Paste")
			(net "GND")
		)
		(pad "AE10" smd circle
			(at -4.400042 7.599934 180)
			(size 0.3556 0.3556)
			(layers "F.Cu" "F.Mask" "F.Paste")
			(net "PCE_VDDH")
		)
		(pad "AE11" smd circle
			(at -3.599942 7.599934 180)
			(size 0.3556 0.3556)
			(layers "F.Cu" "F.Mask" "F.Paste")
			(net "GND")
		)
		(pad "AE12" smd circle
			(at -2.800096 7.599934 180)
			(size 0.3556 0.3556)
			(layers "F.Cu" "F.Mask" "F.Paste")
			(net "PCE_VDDH")
		)
		(pad "AE13" smd circle
			(at -1.999996 7.599934 180)
			(size 0.3556 0.3556)
			(layers "F.Cu" "F.Mask" "F.Paste")
			(net "GND")
		)
		(pad "AE14" smd circle
			(at -1.199896 7.599934 180)
			(size 0.3556 0.3556)
			(layers "F.Cu" "F.Mask" "F.Paste")
			(net "PCE_VDDH")
		)
		(pad "AE15" smd circle
			(at -0.40005 7.599934 180)
			(size 0.3556 0.3556)
			(layers "F.Cu" "F.Mask" "F.Paste")
			(net "GND")
		)
		(pad "AE16" smd circle
			(at 0.40005 7.599934 180)
			(size 0.3556 0.3556)
			(layers "F.Cu" "F.Mask" "F.Paste")
			(net "PCE_VDDH")
		)
		(pad "AE17" smd circle
			(at 1.199896 7.599934 180)
			(size 0.3556 0.3556)
			(layers "F.Cu" "F.Mask" "F.Paste")
			(net "GND")
		)
		(pad "AE18" smd circle
			(at 1.999996 7.599934 180)
			(size 0.3556 0.3556)
			(layers "F.Cu" "F.Mask" "F.Paste")
			(net "GND")
		)
		(pad "AE19" smd circle
			(at 2.800096 7.599934 180)
			(size 0.3556 0.3556)
			(layers "F.Cu" "F.Mask" "F.Paste")
			(net "SPARE5")
		)
		(pad "AE20" smd circle
			(at 3.599942 7.599934 180)
			(size 0.3556 0.3556)
			(layers "F.Cu" "F.Mask" "F.Paste")
			(net "SPARE3")
		)
		(pad "AE21" smd circle
			(at 4.400042 7.599934 180)
			(size 0.3556 0.3556)
			(layers "F.Cu" "F.Mask" "F.Paste")
			(net "IOC_GPIO_7")
		)
		(pad "AE22" smd circle
			(at 5.199888 7.599934 180)
			(size 0.3556 0.3556)
			(layers "F.Cu" "F.Mask" "F.Paste")
			(net "SYS_DBMODE0")
		)
		(pad "AE23" smd circle
			(at 5.999988 7.599934 180)
			(size 0.3556 0.3556)
			(layers "F.Cu" "F.Mask" "F.Paste")
			(net "SYS_RST_N_1")
		)
		(pad "AE24" smd circle
			(at 6.800088 7.599934 180)
			(size 0.3556 0.3556)
			(layers "F.Cu" "F.Mask" "F.Paste")
			(net "GND")
		)
		(pad "AE25" smd circle
			(at 7.599934 7.599934 180)
			(size 0.3556 0.3556)
			(layers "F.Cu" "F.Mask" "F.Paste")
			(net "GND")
		)
		(pad "AE26" smd circle
			(at 8.400034 7.599934 180)
			(size 0.3556 0.3556)
			(layers "F.Cu" "F.Mask" "F.Paste")
			(net "GND")
		)
		(pad "AE27" smd circle
			(at 9.19988 7.599934 180)
			(size 0.3556 0.3556)
			(layers "F.Cu" "F.Mask" "F.Paste")
			(net "P1V8")
		)
		(pad "AE28" smd circle
			(at 9.99998 7.599934 180)
			(size 0.3556 0.3556)
			(layers "F.Cu" "F.Mask" "F.Paste")
			(net "UART_SERCLK")
		)
		(pad "AE29" smd circle
			(at 10.80008 7.599934 180)
			(size 0.3556 0.3556)
			(layers "F.Cu" "F.Mask" "F.Paste")
			(net "IOC_EXT2_LED_Y")
		)
		(pad "AE30" smd circle
			(at 11.599926 7.599934 180)
			(size 0.3556 0.3556)
			(layers "F.Cu" "F.Mask" "F.Paste")
			(net "IOC_GPIO_31")
		)
		(pad "AF1" smd circle
			(at -11.599926 8.400034 180)
			(size 0.3556 0.3556)
			(layers "F.Cu" "F.Mask" "F.Paste")
			(net "SAS0_VDDH")
		)
		(pad "AF2" smd circle
			(at -10.80008 8.400034 180)
			(size 0.3556 0.3556)
			(layers "F.Cu" "F.Mask" "F.Paste")
			(net "GND")
		)
		(pad "AF3" smd circle
			(at -9.99998 8.400034 180)
			(size 0.3556 0.3556)
			(layers "F.Cu" "F.Mask" "F.Paste")
			(net "GND")
		)
		(pad "AF4" smd circle
			(at -9.19988 8.400034 180)
			(size 0.3556 0.3556)
			(layers "F.Cu" "F.Mask" "F.Paste")
			(net "SAS0_AVDD")
		)
		(pad "AF5" smd circle
			(at -8.400034 8.400034 180)
			(size 0.3556 0.3556)
			(layers "F.Cu" "F.Mask" "F.Paste")
			(net "GND")
		)
		(pad "AF6" smd circle
			(at -7.599934 8.400034 180)
			(size 0.3556 0.3556)
			(layers "F.Cu" "F.Mask" "F.Paste")
			(net "GND")
		)
		(pad "AF7" smd circle
			(at -6.800088 8.400034 180)
			(size 0.3556 0.3556)
			(layers "F.Cu" "F.Mask" "F.Paste")
			(net "PCIE_IOM_TO_COMP_8_DN_C")
		)
		(pad "AF8" smd circle
			(at -5.999988 8.400034 180)
			(size 0.3556 0.3556)
			(layers "F.Cu" "F.Mask" "F.Paste")
			(net "PCIE_IOM_TO_COMP_9_DN_C")
		)
		(pad "AF9" smd circle
			(at -5.199888 8.400034 180)
			(size 0.3556 0.3556)
			(layers "F.Cu" "F.Mask" "F.Paste")
			(net "GND")
		)
		(pad "AF10" smd circle
			(at -4.400042 8.400034 180)
			(size 0.3556 0.3556)
			(layers "F.Cu" "F.Mask" "F.Paste")
			(net "PCIE_IOM_TO_COMP_10_DN_C")
		)
		(pad "AF11" smd circle
			(at -3.599942 8.400034 180)
			(size 0.3556 0.3556)
			(layers "F.Cu" "F.Mask" "F.Paste")
			(net "PCIE_IOM_TO_COMP_11_DN_C")
		)
		(pad "AF12" smd circle
			(at -2.800096 8.400034 180)
			(size 0.3556 0.3556)
			(layers "F.Cu" "F.Mask" "F.Paste")
			(net "GND")
		)
		(pad "AF13" smd circle
			(at -1.999996 8.400034 180)
			(size 0.3556 0.3556)
			(layers "F.Cu" "F.Mask" "F.Paste")
			(net "PCIE_IOM_TO_COMP_12_DN_C")
		)
		(pad "AF14" smd circle
			(at -1.199896 8.400034 180)
			(size 0.3556 0.3556)
			(layers "F.Cu" "F.Mask" "F.Paste")
			(net "PCIE_IOM_TO_COMP_13_DN_C")
		)
		(pad "AF15" smd circle
			(at -0.40005 8.400034 180)
			(size 0.3556 0.3556)
			(layers "F.Cu" "F.Mask" "F.Paste")
			(net "GND")
		)
		(pad "AF16" smd circle
			(at 0.40005 8.400034 180)
			(size 0.3556 0.3556)
			(layers "F.Cu" "F.Mask" "F.Paste")
			(net "PCIE_IOM_TO_COMP_14_DN_C")
		)
		(pad "AF17" smd circle
			(at 1.199896 8.400034 180)
			(size 0.3556 0.3556)
			(layers "F.Cu" "F.Mask" "F.Paste")
			(net "PCIE_IOM_TO_COMP_15_DN_C")
		)
		(pad "AF18" smd circle
			(at 1.999996 8.400034 180)
			(size 0.3556 0.3556)
			(layers "F.Cu" "F.Mask" "F.Paste")
			(net "GND")
		)
		(pad "AF19" smd circle
			(at 2.800096 8.400034 180)
			(size 0.3556 0.3556)
			(layers "F.Cu" "F.Mask" "F.Paste")
			(net "GND")
		)
		(pad "AF20" smd circle
			(at 3.599942 8.400034 180)
			(size 0.3556 0.3556)
			(layers "F.Cu" "F.Mask" "F.Paste")
			(net "P1V8")
		)
		(pad "AF21" smd circle
			(at 4.400042 8.400034 180)
			(size 0.3556 0.3556)
			(layers "F.Cu" "F.Mask" "F.Paste")
			(net "GND")
		)
		(pad "AF22" smd circle
			(at 5.199888 8.400034 180)
			(size 0.3556 0.3556)
			(layers "F.Cu" "F.Mask" "F.Paste")
			(net "P1V8")
		)
		(pad "AF23" smd circle
			(at 5.999988 8.400034 180)
			(size 0.3556 0.3556)
			(layers "F.Cu" "F.Mask" "F.Paste")
			(net "GND")
		)
		(pad "AF24" smd circle
			(at 6.800088 8.400034 180)
			(size 0.3556 0.3556)
			(layers "F.Cu" "F.Mask" "F.Paste")
			(net "P1V8")
		)
		(pad "AF25" smd circle
			(at 7.599934 8.400034 180)
			(size 0.3556 0.3556)
			(layers "F.Cu" "F.Mask" "F.Paste")
			(net "GND")
		)
		(pad "AF26" smd circle
			(at 8.400034 8.400034 180)
			(size 0.3556 0.3556)
			(layers "F.Cu" "F.Mask" "F.Paste")
			(net "P1V8")
		)
		(pad "AF27" smd circle
			(at 9.19988 8.400034 180)
			(size 0.3556 0.3556)
			(layers "F.Cu" "F.Mask" "F.Paste")
			(net "GND")
		)
		(pad "AF28" smd circle
			(at 9.99998 8.400034 180)
			(size 0.3556 0.3556)
			(layers "F.Cu" "F.Mask" "F.Paste")
			(net "IOC_GPIO_26")
		)
		(pad "AF29" smd circle
			(at 10.80008 8.400034 180)
			(size 0.3556 0.3556)
			(layers "F.Cu" "F.Mask" "F.Paste")
			(net "IOC_GPIO_0")
		)
		(pad "AF30" smd circle
			(at 11.599926 8.400034 180)
			(size 0.3556 0.3556)
			(layers "F.Cu" "F.Mask" "F.Paste")
			(net "IOC_GPIO_16")
		)
		(pad "AG1" smd circle
			(at -11.599926 9.19988 180)
			(size 0.3556 0.3556)
			(layers "F.Cu" "F.Mask" "F.Paste")
			(net "PHY_IOC_TO_CON_A_1_DP_C")
		)
		(pad "AG2" smd circle
			(at -10.80008 9.19988 180)
			(size 0.3556 0.3556)
			(layers "F.Cu" "F.Mask" "F.Paste")
			(net "PHY_IOC_TO_CON_A_1_DN_C")
		)
		(pad "AG3" smd circle
			(at -9.99998 9.19988 180)
			(size 0.3556 0.3556)
			(layers "F.Cu" "F.Mask" "F.Paste")
			(net "GND")
		)
		(pad "AG4" smd circle
			(at -9.19988 9.19988 180)
			(size 0.3556 0.3556)
			(layers "F.Cu" "F.Mask" "F.Paste")
			(net "PHY_CON_A_TO_IOC_1_DP")
		)
		(pad "AG5" smd circle
			(at -8.400034 9.19988 180)
			(size 0.3556 0.3556)
			(layers "F.Cu" "F.Mask" "F.Paste")
			(net "PHY_CON_A_TO_IOC_1_DN")
		)
		(pad "AG6" smd circle
			(at -7.599934 9.19988 180)
			(size 0.3556 0.3556)
			(layers "F.Cu" "F.Mask" "F.Paste")
			(net "GND")
		)
		(pad "AG7" smd circle
			(at -6.800088 9.19988 180)
			(size 0.3556 0.3556)
			(layers "F.Cu" "F.Mask" "F.Paste")
			(net "PCIE_IOM_TO_COMP_8_DP_C")
		)
		(pad "AG8" smd circle
			(at -5.999988 9.19988 180)
			(size 0.3556 0.3556)
			(layers "F.Cu" "F.Mask" "F.Paste")
			(net "PCIE_IOM_TO_COMP_9_DP_C")
		)
		(pad "AG9" smd circle
			(at -5.199888 9.19988 180)
			(size 0.3556 0.3556)
			(layers "F.Cu" "F.Mask" "F.Paste")
			(net "PCE_VDDH")
		)
		(pad "AG10" smd circle
			(at -4.400042 9.19988 180)
			(size 0.3556 0.3556)
			(layers "F.Cu" "F.Mask" "F.Paste")
			(net "PCIE_IOM_TO_COMP_10_DP_C")
		)
		(pad "AG11" smd circle
			(at -3.599942 9.19988 180)
			(size 0.3556 0.3556)
			(layers "F.Cu" "F.Mask" "F.Paste")
			(net "PCIE_IOM_TO_COMP_11_DP_C")
		)
		(pad "AG12" smd circle
			(at -2.800096 9.19988 180)
			(size 0.3556 0.3556)
			(layers "F.Cu" "F.Mask" "F.Paste")
			(net "PCE_VDDH")
		)
		(pad "AG13" smd circle
			(at -1.999996 9.19988 180)
			(size 0.3556 0.3556)
			(layers "F.Cu" "F.Mask" "F.Paste")
			(net "PCIE_IOM_TO_COMP_12_DP_C")
		)
		(pad "AG14" smd circle
			(at -1.199896 9.19988 180)
			(size 0.3556 0.3556)
			(layers "F.Cu" "F.Mask" "F.Paste")
			(net "PCIE_IOM_TO_COMP_13_DP_C")
		)
		(pad "AG15" smd circle
			(at -0.40005 9.19988 180)
			(size 0.3556 0.3556)
			(layers "F.Cu" "F.Mask" "F.Paste")
			(net "GND")
		)
		(pad "AG16" smd circle
			(at 0.40005 9.19988 180)
			(size 0.3556 0.3556)
			(layers "F.Cu" "F.Mask" "F.Paste")
			(net "PCIE_IOM_TO_COMP_14_DP_C")
		)
		(pad "AG17" smd circle
			(at 1.199896 9.19988 180)
			(size 0.3556 0.3556)
			(layers "F.Cu" "F.Mask" "F.Paste")
			(net "PCIE_IOM_TO_COMP_15_DP_C")
		)
		(pad "AG18" smd circle
			(at 1.999996 9.19988 180)
			(size 0.3556 0.3556)
			(layers "F.Cu" "F.Mask" "F.Paste")
			(net "PCE_VDDH")
		)
		(pad "AG19" smd circle
			(at 2.800096 9.19988 180)
			(size 0.3556 0.3556)
			(layers "F.Cu" "F.Mask" "F.Paste")
			(net "P1V8")
		)
		(pad "AG20" smd circle
			(at 3.599942 9.19988 180)
			(size 0.3556 0.3556)
			(layers "F.Cu" "F.Mask" "F.Paste")
			(net "GND")
		)
		(pad "AG21" smd circle
			(at 4.400042 9.19988 180)
			(size 0.3556 0.3556)
			(layers "F.Cu" "F.Mask" "F.Paste")
			(net "P1V8")
		)
		(pad "AG22" smd circle
			(at 5.199888 9.19988 180)
			(size 0.3556 0.3556)
			(layers "F.Cu" "F.Mask" "F.Paste")
			(net "GND")
		)
		(pad "AG23" smd circle
			(at 5.999988 9.19988 180)
			(size 0.3556 0.3556)
			(layers "F.Cu" "F.Mask" "F.Paste")
			(net "P1V8")
		)
		(pad "AG24" smd circle
			(at 6.800088 9.19988 180)
			(size 0.3556 0.3556)
			(layers "F.Cu" "F.Mask" "F.Paste")
			(net "GND")
		)
		(pad "AG25" smd circle
			(at 7.599934 9.19988 180)
			(size 0.3556 0.3556)
			(layers "F.Cu" "F.Mask" "F.Paste")
			(net "P1V8")
		)
		(pad "AG26" smd circle
			(at 8.400034 9.19988 180)
			(size 0.3556 0.3556)
			(layers "F.Cu" "F.Mask" "F.Paste")
			(net "GND")
		)
	)
)
